#ISCELL
  pure_quanta quanta_title_block_c *
  *
#ISCELL
  standard tap *
  page415_i1
#ISCELL
  standard tap *
  page415_i10
#ISCELL
  standard tap *
  page415_i11
#ISCELL
  standard tap *
  page415_i12
#ISCELL
  standard tap *
  page415_i13
#ISCELL
  standard tap *
  page415_i14
#ISCELL
  standard tap *
  page415_i15
#ISCELL
  standard tap *
  page415_i16
#ISCELL
  standard offpage *
  page415_i17
#ISCELL
  standard offpage *
  page415_i18
#ISCELL
  standard tap *
  page415_i19
#ISCELL
  standard tap *
  page415_i2
#ISCELL
  standard tap *
  page415_i20
#ISCELL
  standard tap *
  page415_i21
#ISCELL
  standard tap *
  page415_i22
#ISCELL
  standard tap *
  page415_i23
#ISCELL
  standard tap *
  page415_i24
#ISCELL
  standard tap *
  page415_i25
#ISCELL
  standard tap *
  page415_i26
#ISCELL
  standard tap *
  page415_i27
#ISCELL
  standard tap *
  page415_i28
#ISCELL
  standard tap *
  page415_i29
#ISCELL
  standard tap *
  page415_i3
#ISCELL
  standard tap *
  page415_i30
#ISCELL
  standard tap *
  page415_i31
#ISCELL
  standard tap *
  page415_i32
#ISCELL
  standard tap *
  page415_i33
#ISCELL
  standard tap *
  page415_i34
#ISCELL
  standard offpage *
  page415_i35
#ISCELL
  standard offpage *
  page415_i36
#CELL
  pure_quanta pt5161lrs *
  page415_i37
#CELL
  pure_quanta pt5161lrs *
  page415_i38
#ISCELL
  standard tap *
  page415_i4
#ISCELL
  standard tap *
  page415_i5
#ISCELL
  standard tap *
  page415_i6
#ISCELL
  standard tap *
  page415_i7
#ISCELL
  standard tap *
  page415_i8
#ISCELL
  standard tap *
  page415_i9
